FILE_TYPE = CONNECTIVITY;
{Allegro Design Entry HDL 16.6-p007 (v16-6-112F) 10/10/2012}
"PAGE_NUMBER" = 85;
0"NC";
1"M_L_DQS_DP<17:0>";
2"M_L_DQS_DN<17:0>";
3"M_L_MA<17:0>";
4"M_L_DQ<63:0>";
5"M_L_CS_N<7:0>";
6"M_L_CKE<3:0>";
7"M_L_ODT<3:0>";
8"M_L_CLK_DN<3:0>";
9"M_L_ECC<7:0>";
10"M_L_CLK_DP<3:0>";
11"M_L_BA<1:0>";
12"M_L_BG<1:0>";
13"PVDDQ_KLM\g";
14"PVTT_KLM\g";
15"GND\g";
16"GND\g";
17"GND\g";
18"PVPP_KLM\g";
19"PVPP_KLM\g";
20"P12V_NVDIMM_KLM\g";
21"GND\g";
22"M_L_ACT_N";
23"M_L_VREF";
24"TP_CH_L_DIMM_L0_RFU_2";
25"TP_CH_L_DIMM_L0_RFU_0";
26"TP_CH_L_DIMM_L0_RFU_1";
27"SMB_DDR_KLM_VPP_SDA";
28"SMB_DDR_KLM_VPP_SCL";
29"FM_ADR_COMPLETE_KLM_N";
30"FM_DIMM_EVENT_COD_N";
31"M_L_PAR";
32"M_KLM_RST_N";
33"M_L_C<2>";
34"M_L_BG<0>";
35"M_L_BG<1>";
36"M_L_BA<0>";
37"M_L_BA<1>";
38"M_L_CLK_DP<1>";
39"M_L_CLK_DN<1>";
40"M_L_CS_N<3>";
41"M_L_CLK_DP<0>";
42"M_L_CS_N<2>";
43"M_L_CS_N<1>";
44"M_L_MA<0>";
45"M_L_ECC<7>";
46"M_L_ECC<4>";
47"M_L_ECC<5>";
48"M_L_ECC<2>";
49"M_L_ECC<3>";
50"M_L_ECC<0>";
51"M_L_ECC<1>";
52"M_L_CLK_DN<0>";
53"M_L_CKE<1>";
54"M_L_ECC<6>";
55"M_L_ODT<0>";
56"M_L_ODT<1>";
57"M_L_CKE<0>";
58"M_L_CS_N<0>";
59"M_L_ALERT_N";
60"M_L_DQ<1>";
61"M_L_DQ<0>";
62"M_L_DQ<3>";
63"M_L_DQ<2>";
64"M_L_DQ<5>";
65"M_L_DQ<4>";
66"M_L_DQ<10>";
67"M_L_DQ<11>";
68"M_L_DQ<8>";
69"M_L_DQ<9>";
70"M_L_DQ<6>";
71"M_L_DQ<7>";
72"M_L_DQ<17>";
73"M_L_DQ<15>";
74"M_L_DQ<12>";
75"M_L_DQ<13>";
76"M_L_DQ<14>";
77"M_L_DQ<18>";
78"M_L_DQ<20>";
79"M_L_DQ<21>";
80"M_L_DQ<19>";
81"M_L_DQ<16>";
82"M_L_DQ<23>";
83"M_L_DQ<22>";
84"M_L_DQ<25>";
85"M_L_DQ<24>";
86"M_L_DQ<27>";
87"M_L_DQ<28>";
88"M_L_DQ<29>";
89"M_L_DQ<30>";
90"M_L_DQ<31>";
91"M_L_DQ<26>";
92"M_L_DQ<32>";
93"M_L_DQ<35>";
94"M_L_DQ<33>";
95"M_L_DQ<34>";
96"M_L_DQ<37>";
97"M_L_DQ<36>";
98"M_L_DQ<38>";
99"M_L_DQ<40>";
100"M_L_DQ<41>";
101"M_L_DQ<39>";
102"M_L_DQ<42>";
103"M_L_DQ<45>";
104"M_L_DQ<44>";
105"M_L_DQ<47>";
106"M_L_DQ<43>";
107"M_L_MA<1>";
108"M_L_MA<12>";
109"M_L_MA<13>";
110"M_L_MA<17>";
111"M_L_MA<3>";
112"M_L_MA<4>";
113"M_L_MA<5>";
114"M_L_MA<6>";
115"M_L_MA<7>";
116"M_L_MA<8>";
117"M_L_MA<9>";
118"M_L_MA<2>";
119"M_L_MA<10>";
120"M_L_MA<11>";
121"M_L_MA<14>";
122"M_L_MA<15>";
123"M_L_MA<16>";
124"M_L_DQ<46>";
125"M_L_DQ<49>";
126"M_L_DQ<48>";
127"M_L_DQ<51>";
128"M_L_DQ<50>";
129"M_L_DQ<53>";
130"M_L_DQ<54>";
131"M_L_DQ<57>";
132"M_L_DQ<56>";
133"M_L_DQ<55>";
134"M_L_DQ<52>";
135"M_L_DQ<60>";
136"M_L_DQ<59>";
137"M_L_DQ<61>";
138"M_L_DQ<58>";
139"M_L_DQ<63>";
140"M_L_DQ<62>";
141"M_L_DQS_DN<0>";
142"M_L_DQS_DP<0>";
143"M_L_DQS_DN<1>";
144"M_L_DQS_DP<1>";
145"M_L_DQS_DN<2>";
146"M_L_DQS_DP<2>";
147"M_L_DQS_DN<3>";
148"M_L_DQS_DP<3>";
149"M_L_DQS_DN<4>";
150"M_L_DQS_DP<4>";
151"M_L_DQS_DN<5>";
152"M_L_DQS_DP<5>";
153"M_L_DQS_DN<6>";
154"M_L_DQS_DP<6>";
155"M_L_DQS_DN<10>";
156"M_L_DQS_DP<10>";
157"M_L_DQS_DN<11>";
158"M_L_DQS_DP<11>";
159"M_L_DQS_DN<12>";
160"M_L_DQS_DP<12>";
161"M_L_DQS_DN<13>";
162"M_L_DQS_DP<13>";
163"M_L_DQS_DN<14>";
164"M_L_DQS_DP<14>";
165"M_L_DQS_DN<15>";
166"M_L_DQS_DP<15>";
167"M_L_DQS_DN<16>";
168"M_L_DQS_DP<16>";
169"M_L_DQS_DN<17>";
170"M_L_DQS_DN<7>";
171"M_L_DQS_DP<7>";
172"M_L_DQS_DN<8>";
173"M_L_DQS_DP<8>";
174"M_L_DQS_DN<9>";
175"M_L_DQS_DP<9>";
176"M_L_DQS_DP<17>";
%"TAP"
"6","(700,4850)","2","mstr_standard","I10";
;
HDL_TAP"TRUE"
BODY_TYPE"PLUMBING"
CDS_LIB"mstr_standard";
"B \NAC \NWC"1;
"S \NAC"
BN"14"164;
%"TAP"
"6","(-1750,2200)","2","mstr_standard","I100";
;
HDL_TAP"TRUE"
BODY_TYPE"PLUMBING"
CDS_LIB"mstr_standard";
"B \NAC \NWC"4;
"S \NAC"
BN"8"68;
%"TAP"
"6","(-1750,2250)","2","mstr_standard","I101";
;
HDL_TAP"TRUE"
BODY_TYPE"PLUMBING"
CDS_LIB"mstr_standard";
"B \NAC \NWC"4;
"S \NAC"
BN"11"67;
%"TAP"
"6","(-1750,1950)","2","mstr_standard","I102";
;
HDL_TAP"TRUE"
BODY_TYPE"PLUMBING"
CDS_LIB"mstr_standard";
"B \NAC \NWC"4;
"S \NAC"
BN"5"64;
%"TAP"
"6","(-1750,1900)","2","mstr_standard","I103";
;
HDL_TAP"TRUE"
BODY_TYPE"PLUMBING"
CDS_LIB"mstr_standard";
"B \NAC \NWC"4;
"S \NAC"
BN"2"63;
%"TAP"
"6","(-1750,2000)","2","mstr_standard","I104";
;
HDL_TAP"TRUE"
BODY_TYPE"PLUMBING"
CDS_LIB"mstr_standard";
"B \NAC \NWC"4;
"S \NAC"
BN"4"65;
%"TAP"
"6","(-1750,2050)","2","mstr_standard","I105";
;
HDL_TAP"TRUE"
BODY_TYPE"PLUMBING"
CDS_LIB"mstr_standard";
"B \NAC \NWC"4;
"S \NAC"
BN"7"71;
%"TAP"
"6","(-1750,2150)","2","mstr_standard","I106";
;
HDL_TAP"TRUE"
BODY_TYPE"PLUMBING"
CDS_LIB"mstr_standard";
"B \NAC \NWC"4;
"S \NAC"
BN"9"69;
%"TAP"
"6","(-1750,2100)","2","mstr_standard","I107";
;
HDL_TAP"TRUE"
BODY_TYPE"PLUMBING"
CDS_LIB"mstr_standard";
"B \NAC \NWC"4;
"S \NAC"
BN"6"70;
%"TAP"
"6","(-1750,1750)","2","mstr_standard","I108";
;
HDL_TAP"TRUE"
BODY_TYPE"PLUMBING"
CDS_LIB"mstr_standard";
"B \NAC \NWC"4;
"S \NAC"
BN"1"60;
%"TAP"
"6","(-1750,1850)","2","mstr_standard","I109";
;
HDL_TAP"TRUE"
BODY_TYPE"PLUMBING"
CDS_LIB"mstr_standard";
"B \NAC \NWC"4;
"S \NAC"
BN"3"62;
%"TAP"
"6","(700,4950)","2","mstr_standard","I11";
;
HDL_TAP"TRUE"
BODY_TYPE"PLUMBING"
CDS_LIB"mstr_standard";
"B \NAC \NWC"1;
"S \NAC"
BN"15"166;
%"TAP"
"6","(-1750,1800)","2","mstr_standard","I110";
;
HDL_TAP"TRUE"
BODY_TYPE"PLUMBING"
CDS_LIB"mstr_standard";
"B \NAC \NWC"4;
"S \NAC"
BN"0"61;
%"SCONN288_H44441004"
"1","(-2500,3250)","0","mstr_sconn","I111";
;
CDS_SEC"1"
ROOM"DDR4_CH_L"
CDS_LOCATION"J1A2"
SEC"1"
SEC_TYPE"PIP"
CDS_LIB"mstr_sconn"
BOM_COST"MEM"
PACK_TYPE"PIP"
MATERIAL"SCONN"
PART_NUMBER"H44441-004"
LOCATION"J1A2";
"DQ<63>"
$PN"280"140;
"DQ<62>"
$PN"135"139;
"DQ<61>"
$PN"273"135;
"DQ<5>"
$PN"148"65;
"DQ<4>"
$PN"3"64;
"DQ<3>"
$PN"157"63;
"DQ<2>"
$PN"12"62;
"DQ<47>"
$PN"258"124;
"DQ<48>"
$PN"119"125;
"DQ<49>"
$PN"264"126;
"DQ<50>"
$PN"126"127;
"DQ<51>"
$PN"271"128;
"DQ<52>"
$PN"117"129;
"DQ<53>"
$PN"262"134;
"DQ<54>"
$PN"124"133;
"DQ<58>"
$PN"137"136;
"DQ<57>"
$PN"275"132;
"SAVE_N_NC"
$PN"230"29;
"RFU<1>"
$PN"227"26;
"RFU<0>"
$PN"205"25;
"DQ<17>"
$PN"172"81;
"DQ<15>"
$PN"166"76;
"DQ<26>"
$PN"45"86;
"DQ<27>"
$PN"190"91;
"S0_N"
$PN"84"58;
"CKE<0>"
$PN"60"57;
"ODT<1>"
$PN"91"56;
"ODT<0>"
$PN"87"55;
"CB<7>"
$PN"199"54;
"A16_RAS_N"
$PN"82"123;
"A15_CAS_N"
$PN"86"122;
"A14_WE_N"
$PN"228"121;
"A11"
$PN"210"120;
"A10"
$PN"225"119;
"DQ<38>"
$PN"102"101;
"DQ<36>"
$PN"95"96;
"DQ<35>"
$PN"249"95;
"A2"
$PN"216"118;
"ALERT_N"
$PN"208"59;
"ACT_N"
$PN"62"22;
"DQ<0>"
$PN"5"60;
"DQ<1>"
$PN"150"61;
"SA<1>"
$PN"140"19;
"SA<2>"
$PN"238"16;
"VDDSPD"
$PN"284"19;
"SA<0>"
$PN"139"16;
"BA<0>"
$PN"81"36;
"BG<1>"
$PN"207"35;
"BG<0>"
$PN"63"34;
"CK1P"
$PN"218"38;
"VREFCA"
$PN"146"23;
"SDA"
$PN"285"27;
"SCL"
$PN"141"28;
"RFU<2>"
$PN"144"24;
"RESET_N"
$PN"58"32;
"PAR"
$PN"222"31;
"EVENT_N"
$PN"78"30;
"DQ<6>"
$PN"10"71;
"DQ<7>"
$PN"155"70;
"DQ<8>"
$PN"16"69;
"DQ<9>"
$PN"161"68;
"DQ<10>"
$PN"23"67;
"DQ<11>"
$PN"168"66;
"DQ<12>"
$PN"14"75;
"DQ<13>"
$PN"159"74;
"DQ<14>"
$PN"21"73;
"DQ<16>"
$PN"27"72;
"DQ<18>"
$PN"34"80;
"DQ<19>"
$PN"179"77;
"DQ<20>"
$PN"25"79;
"DQ<21>"
$PN"170"78;
"DQ<22>"
$PN"32"82;
"DQ<23>"
$PN"177"83;
"DQ<24>"
$PN"38"84;
"DQ<25>"
$PN"183"85;
"DQ<30>"
$PN"43"90;
"DQ<31>"
$PN"188"89;
"DQ<32>"
$PN"97"94;
"DQ<33>"
$PN"242"92;
"DQ<34>"
$PN"104"93;
"DQ<37>"
$PN"240"97;
"DQ<39>"
$PN"247"98;
"DQ<40>"
$PN"108"100;
"DQ<41>"
$PN"253"99;
"DQ<42>"
$PN"115"106;
"DQ<43>"
$PN"260"102;
"DQ<44>"
$PN"106"103;
"DQ<45>"
$PN"251"104;
"DQ<46>"
$PN"113"105;
"DQ<55>"
$PN"269"130;
"DQ<56>"
$PN"130"131;
"DQ<59>"
$PN"282"138;
"DQ<60>"
$PN"128"137;
"CKE<1>"
$PN"203"53;
"CK0N"
$PN"75"52;
"CB<0>"
$PN"49"51;
"CB<1>"
$PN"194"50;
"CB<2>"
$PN"56"49;
"CB<3>"
$PN"201"48;
"CB<4>"
$PN"47"47;
"CB<5>"
$PN"192"46;
"CB<6>"
$PN"54"45;
"A9"
$PN"66"117;
"A8"
$PN"68"116;
"A7"
$PN"211"115;
"A6"
$PN"69"114;
"A5"
$PN"213"113;
"A4"
$PN"214"112;
"A3"
$PN"71"111;
"A17"
$PN"234"110;
"A13"
$PN"232"109;
"A12"
$PN"65"108;
"A1"
$PN"72"107;
"A0"
$PN"79"44;
"C<2>"
$PN"235"33;
"DQ<28>"
$PN"36"88;
"DQ<29>"
$PN"181"87;
"S1_N"
$PN"89"43;
"S2_N_C<0>"
$PN"93"42;
"S3_N_C<1>"
$PN"237"40;
"CK0P"
$PN"74"41;
"CK1N"
$PN"219"39;
"BA<1>"
$PN"224"37;
%"TAP"
"6","(-3250,4850)","0","mstr_standard","I112";
;
HDL_TAP"TRUE"
BODY_TYPE"PLUMBING"
CDS_LIB"mstr_standard";
"B \NAC \NWC"3;
"S \NAC"
BN"16"123;
%"TAP"
"6","(-3250,4900)","0","mstr_standard","I113";
;
HDL_TAP"TRUE"
BODY_TYPE"PLUMBING"
CDS_LIB"mstr_standard";
"B \NAC \NWC"3;
"S \NAC"
BN"17"110;
%"TAP"
"6","(-3250,4800)","0","mstr_standard","I114";
;
HDL_TAP"TRUE"
BODY_TYPE"PLUMBING"
CDS_LIB"mstr_standard";
"B \NAC \NWC"3;
"S \NAC"
BN"15"122;
%"TAP"
"6","(-3250,4750)","0","mstr_standard","I115";
;
HDL_TAP"TRUE"
BODY_TYPE"PLUMBING"
CDS_LIB"mstr_standard";
"B \NAC \NWC"3;
"S \NAC"
BN"14"121;
%"TAP"
"6","(-3250,4700)","0","mstr_standard","I116";
;
HDL_TAP"TRUE"
BODY_TYPE"PLUMBING"
CDS_LIB"mstr_standard";
"B \NAC \NWC"3;
"S \NAC"
BN"13"109;
%"TAP"
"6","(-3250,4650)","0","mstr_standard","I117";
;
HDL_TAP"TRUE"
BODY_TYPE"PLUMBING"
CDS_LIB"mstr_standard";
"B \NAC \NWC"3;
"S \NAC"
BN"12"108;
%"TAP"
"6","(-3250,4600)","0","mstr_standard","I118";
;
HDL_TAP"TRUE"
BODY_TYPE"PLUMBING"
CDS_LIB"mstr_standard";
"B \NAC \NWC"3;
"S \NAC"
BN"11"120;
%"TAP"
"6","(-3250,4550)","0","mstr_standard","I119";
;
HDL_TAP"TRUE"
BODY_TYPE"PLUMBING"
CDS_LIB"mstr_standard";
"B \NAC \NWC"3;
"S \NAC"
BN"10"119;
%"TAP"
"6","(700,5050)","2","mstr_standard","I12";
;
HDL_TAP"TRUE"
BODY_TYPE"PLUMBING"
CDS_LIB"mstr_standard";
"B \NAC \NWC"1;
"S \NAC"
BN"16"168;
%"TAP"
"6","(-3250,4500)","0","mstr_standard","I120";
;
HDL_TAP"TRUE"
BODY_TYPE"PLUMBING"
CDS_LIB"mstr_standard";
"B \NAC \NWC"3;
"S \NAC"
BN"9"117;
%"TAP"
"6","(-3250,4450)","0","mstr_standard","I121";
;
HDL_TAP"TRUE"
BODY_TYPE"PLUMBING"
CDS_LIB"mstr_standard";
"B \NAC \NWC"3;
"S \NAC"
BN"8"116;
%"TAP"
"6","(-3250,4400)","0","mstr_standard","I122";
;
HDL_TAP"TRUE"
BODY_TYPE"PLUMBING"
CDS_LIB"mstr_standard";
"B \NAC \NWC"3;
"S \NAC"
BN"7"115;
%"TAP"
"6","(-3250,4350)","0","mstr_standard","I123";
;
HDL_TAP"TRUE"
BODY_TYPE"PLUMBING"
CDS_LIB"mstr_standard";
"B \NAC \NWC"3;
"S \NAC"
BN"6"114;
%"TAP"
"6","(-3250,4300)","0","mstr_standard","I124";
;
HDL_TAP"TRUE"
BODY_TYPE"PLUMBING"
CDS_LIB"mstr_standard";
"B \NAC \NWC"3;
"S \NAC"
BN"5"113;
%"TAP"
"6","(-3250,4250)","0","mstr_standard","I125";
;
HDL_TAP"TRUE"
BODY_TYPE"PLUMBING"
CDS_LIB"mstr_standard";
"B \NAC \NWC"3;
"S \NAC"
BN"4"112;
%"TAP"
"6","(-3250,4150)","0","mstr_standard","I126";
;
HDL_TAP"TRUE"
BODY_TYPE"PLUMBING"
CDS_LIB"mstr_standard";
"B \NAC \NWC"3;
"S \NAC"
BN"2"118;
%"TAP"
"6","(-3250,4200)","0","mstr_standard","I127";
;
HDL_TAP"TRUE"
BODY_TYPE"PLUMBING"
CDS_LIB"mstr_standard";
"B \NAC \NWC"3;
"S \NAC"
BN"3"111;
%"TAP"
"6","(-3250,4100)","0","mstr_standard","I128";
;
HDL_TAP"TRUE"
BODY_TYPE"PLUMBING"
CDS_LIB"mstr_standard";
"B \NAC \NWC"3;
"S \NAC"
BN"1"107;
%"TAP"
"6","(-3250,4050)","0","mstr_standard","I129";
;
HDL_TAP"TRUE"
BODY_TYPE"PLUMBING"
CDS_LIB"mstr_standard";
"B \NAC \NWC"3;
"S \NAC"
BN"0"44;
%"TAP"
"6","(700,4550)","2","mstr_standard","I13";
;
HDL_TAP"TRUE"
BODY_TYPE"PLUMBING"
CDS_LIB"mstr_standard";
"B \NAC \NWC"1;
"S \NAC"
BN"11"158;
%"TAP"
"6","(-3250,3950)","0","mstr_standard","I130";
;
HDL_TAP"TRUE"
BODY_TYPE"PLUMBING"
CDS_LIB"mstr_standard";
"B \NAC \NWC"11;
"S \NAC"
BN"1"37;
%"TAP"
"6","(-3250,3900)","0","mstr_standard","I133";
;
HDL_TAP"TRUE"
BODY_TYPE"PLUMBING"
CDS_LIB"mstr_standard";
"B \NAC \NWC"11;
"S \NAC"
BN"0"36;
%"TAP"
"6","(-3250,3850)","0","mstr_standard","I134";
;
HDL_TAP"TRUE"
BODY_TYPE"PLUMBING"
CDS_LIB"mstr_standard";
"B \NAC \NWC"12;
"S \NAC"
BN"1"35;
%"TAP"
"6","(-3250,3800)","0","mstr_standard","I135";
;
HDL_TAP"TRUE"
BODY_TYPE"PLUMBING"
CDS_LIB"mstr_standard";
"B \NAC \NWC"12;
"S \NAC"
BN"0"34;
%"TAP"
"6","(-3250,2850)","0","mstr_standard","I138";
;
HDL_TAP"TRUE"
BODY_TYPE"PLUMBING"
CDS_LIB"mstr_standard";
"B \NAC \NWC"9;
"S \NAC"
BN"6"54;
%"TAP"
"6","(-3250,2800)","0","mstr_standard","I139";
;
HDL_TAP"TRUE"
BODY_TYPE"PLUMBING"
CDS_LIB"mstr_standard";
"B \NAC \NWC"9;
"S \NAC"
BN"7"45;
%"TAP"
"6","(700,4650)","2","mstr_standard","I14";
;
HDL_TAP"TRUE"
BODY_TYPE"PLUMBING"
CDS_LIB"mstr_standard";
"B \NAC \NWC"1;
"S \NAC"
BN"12"160;
%"TAP"
"6","(-3250,2750)","0","mstr_standard","I140";
;
HDL_TAP"TRUE"
BODY_TYPE"PLUMBING"
CDS_LIB"mstr_standard";
"B \NAC \NWC"9;
"S \NAC"
BN"4"46;
%"TAP"
"6","(-3250,2700)","0","mstr_standard","I141";
;
HDL_TAP"TRUE"
BODY_TYPE"PLUMBING"
CDS_LIB"mstr_standard";
"B \NAC \NWC"9;
"S \NAC"
BN"5"47;
%"TAP"
"6","(-3250,2650)","0","mstr_standard","I142";
;
HDL_TAP"TRUE"
BODY_TYPE"PLUMBING"
CDS_LIB"mstr_standard";
"B \NAC \NWC"9;
"S \NAC"
BN"2"48;
%"TAP"
"6","(-3250,2600)","0","mstr_standard","I143";
;
HDL_TAP"TRUE"
BODY_TYPE"PLUMBING"
CDS_LIB"mstr_standard";
"B \NAC \NWC"9;
"S \NAC"
BN"3"49;
%"TAP"
"6","(-3250,2550)","0","mstr_standard","I144";
;
HDL_TAP"TRUE"
BODY_TYPE"PLUMBING"
CDS_LIB"mstr_standard";
"B \NAC \NWC"9;
"S \NAC"
BN"0"50;
%"TAP"
"6","(-3250,2500)","0","mstr_standard","I145";
;
HDL_TAP"TRUE"
BODY_TYPE"PLUMBING"
CDS_LIB"mstr_standard";
"B \NAC \NWC"9;
"S \NAC"
BN"1"51;
%"TAP"
"6","(700,4750)","2","mstr_standard","I15";
;
HDL_TAP"TRUE"
BODY_TYPE"PLUMBING"
CDS_LIB"mstr_standard";
"B \NAC \NWC"1;
"S \NAC"
BN"13"162;
%"TAP"
"6","(-3250,3700)","0","mstr_standard","I152";
;
HDL_TAP"TRUE"
BODY_TYPE"PLUMBING"
CDS_LIB"mstr_standard";
"B \NAC \NWC"10;
"S \NAC"
BN"1"38;
%"TAP"
"6","(-3250,3600)","0","mstr_standard","I153";
;
HDL_TAP"TRUE"
BODY_TYPE"PLUMBING"
CDS_LIB"mstr_standard";
"B \NAC \NWC"10;
"S \NAC"
BN"0"41;
%"TAP"
"6","(-3450,3650)","0","mstr_standard","I154";
;
HDL_TAP"TRUE"
BODY_TYPE"PLUMBING"
CDS_LIB"mstr_standard";
"B \NAC \NWC"8;
"S \NAC"
BN"1"39;
%"TAP"
"6","(-3450,3550)","0","mstr_standard","I155";
;
HDL_TAP"TRUE"
BODY_TYPE"PLUMBING"
CDS_LIB"mstr_standard";
"B \NAC \NWC"8;
"S \NAC"
BN"0"52;
%"TAP"
"6","(-3250,3400)","0","mstr_standard","I159";
;
HDL_TAP"TRUE"
BODY_TYPE"PLUMBING"
CDS_LIB"mstr_standard";
"B \NAC \NWC"5;
"S \NAC"
BN"3"40;
%"PVDDQ_KLM"
"1","(-1350,2625)","0","mstr_symbols","I16";
;
HDL_POWER"PVDDQ_KLM"
ROOM"DDR4_CH_D"
BODY_TYPE"PLUMBING"
CDS_LIB"mstr_symbols"
BOM_COST"MEM"
VOLTAGE"1.2V";
"G\NAC"13;
%"TAP"
"6","(-3250,3350)","0","mstr_standard","I160";
;
HDL_TAP"TRUE"
BODY_TYPE"PLUMBING"
CDS_LIB"mstr_standard";
"B \NAC \NWC"5;
"S \NAC"
BN"2"42;
%"TAP"
"6","(-3250,3300)","0","mstr_standard","I161";
;
HDL_TAP"TRUE"
BODY_TYPE"PLUMBING"
CDS_LIB"mstr_standard";
"B \NAC \NWC"5;
"S \NAC"
BN"1"43;
%"TAP"
"6","(-3250,3250)","0","mstr_standard","I162";
;
HDL_TAP"TRUE"
BODY_TYPE"PLUMBING"
CDS_LIB"mstr_standard";
"B \NAC \NWC"5;
"S \NAC"
BN"0"58;
%"TAP"
"6","(-3250,3150)","0","mstr_standard","I163";
;
HDL_TAP"TRUE"
BODY_TYPE"PLUMBING"
CDS_LIB"mstr_standard";
"B \NAC \NWC"6;
"S \NAC"
BN"1"53;
%"TAP"
"6","(-3250,3100)","0","mstr_standard","I166";
;
HDL_TAP"TRUE"
BODY_TYPE"PLUMBING"
CDS_LIB"mstr_standard";
"B \NAC \NWC"6;
"S \NAC"
BN"0"57;
%"TAP"
"6","(-3250,3000)","0","mstr_standard","I167";
;
HDL_TAP"TRUE"
BODY_TYPE"PLUMBING"
CDS_LIB"mstr_standard";
"B \NAC \NWC"7;
"S \NAC"
BN"1"56;
%"TAP"
"6","(-3250,2950)","0","mstr_standard","I168";
;
HDL_TAP"TRUE"
BODY_TYPE"PLUMBING"
CDS_LIB"mstr_standard";
"B \NAC \NWC"7;
"S \NAC"
BN"0"55;
%"PVTT_KLM"
"1","(-1100,2750)","0","mstr_symbols","I17";
;
HDL_POWER"PVTT_KLM"
ROOM"DDR4_CH_D"
BODY_TYPE"PLUMBING"
CDS_LIB"mstr_symbols"
BOM_COST"MEM"
VOLTAGE"0.6V";
"G\NAC"14;
%"SCONN288_H44441004"
"4","(-250,2050)","0","mstr_sconn","I172";
;
CDS_SEC"4"
ROOM"DDR4_CH_L"
CDS_LOCATION"J1A2"
SEC"4"
SEC_TYPE"PIP"
CDS_LIB"mstr_sconn"
BOM_COST"MEM"
PACK_TYPE"PIP"
MATERIAL"SCONN"
PART_NUMBER"H44441-004"
LOCATION"J1A2";
"VPP<4>"
$PN"142"18;
"VTT<1>"
$PN"77"14;
"VPP<0>"
$PN"287"18;
"VPP<1>"
$PN"286"18;
"VPP<2>"
$PN"288"18;
"VPP<3>"
$PN"143"18;
"VDD<1>"
$PN"233"13;
"VDD<2>"
$PN"231"13;
"VDD<3>"
$PN"229"13;
"VDD<4>"
$PN"226"13;
"VDD<5>"
$PN"223"13;
"VDD<7>"
$PN"217"13;
"VDD<8>"
$PN"215"13;
"VDD<9>"
$PN"212"13;
"VDD<11>"
$PN"206"13;
"VDD<12>"
$PN"204"13;
"VDD<14>"
$PN"90"13;
"VDD<15>"
$PN"88"13;
"VDD<17>"
$PN"83"13;
"VDD<18>"
$PN"80"13;
"VDD<20>"
$PN"73"13;
"VDD<21>"
$PN"70"13;
"VDD<22>"
$PN"67"13;
"VDD<24>"
$PN"61"13;
"12V<0>"
$PN"145"20;
"12V<1>"
$PN"1"20;
"VTT<0>"
$PN"221"14;
"VDD<25>"
$PN"59"13;
"VDD<23>"
$PN"64"13;
"VDD<19>"
$PN"76"13;
"VDD<16>"
$PN"85"13;
"VDD<13>"
$PN"92"13;
"VDD<10>"
$PN"209"13;
"VDD<6>"
$PN"220"13;
"VDD<0>"
$PN"236"13;
%"GND"
"1","(2500,1100)","2","mstr_symbols","I173";
;
HDL_POWER"GND"
ROOM"DDR4_CH_D"
BODY_TYPE"PLUMBING"
SIZE"1B"
CDS_LIB"mstr_symbols"
BOM_COST"MEM"
VOLTAGE"0";
"A\NAC"15;
%"GND"
"1","(-5150,1850)","2","mstr_symbols","I175";
;
HDL_POWER"GND"
ROOM"DDR4_CH_D"
BODY_TYPE"PLUMBING"
CDS_LIB"mstr_symbols"
SIZE"1B"
BOM_COST"MEM"
VOLTAGE"0";
"A\NAC"16;
%"GND"
"1","(-4650,1300)","0","mstr_symbols","I180";
;
HDL_POWER"GND"
ROOM"DDR4_CH_D"
BODY_TYPE"PLUMBING"
SIZE"1B"
CDS_LIB"mstr_symbols"
BOM_COST"MEM"
VOLTAGE"0";
"A\NAC"17;
%"CAP_A"
"1","(-4650,1550)","2","dev_discrete","I181";
;
ROOM"DDR4_CH_L"
$SEC"1"
CDS_SEC"1"
CDS_LIB"dev_discrete"
BOM_COST"MEM"
CDS_LOCATION"C9L7"
MATERIAL"X7R"
VOLTAGE"25V"
PACK_TYPE"0402V"
TOLERANCE"10%"
VALUE"0.01UF"
PART_NUMBER"A36096-045"
LOCATION"C9L7";
"B"
$PN"2"17;
"A"
$PN"1"23;
%"PVPP_KLM"
"1","(-950,3075)","0","mstr_symbols","I182";
;
HDL_POWER"PVPP_KLM"
ROOM"DDR4_CH_D"
BODY_TYPE"PLUMBING"
CDS_LIB"mstr_symbols"
BOM_COST"MEM"
VOLTAGE"2.5V";
"G\NAC"18;
%"PVPP_KLM"
"1","(-5150,2250)","0","mstr_symbols","I183";
;
HDL_POWER"PVPP_KLM"
ROOM"DDR4_CH_M"
BODY_TYPE"PLUMBING"
CDS_LIB"mstr_symbols"
BOM_COST"MEM"
VOLTAGE"2.5V";
"G\NAC"19;
%"P12V_NVDIMM_KLM"
"1","(375,3025)","0","mstr_symbols","I185";
;
HDL_POWER"P12V_NVDIMM_KLM"
BODY_TYPE"PLUMBING"
CDS_LIB"mstr_symbols"
VOLTAGE"12.0";
"G\NAC"20;
%"TAP"
"6","(900,4500)","2","mstr_standard","I19";
;
HDL_TAP"TRUE"
BODY_TYPE"PLUMBING"
CDS_LIB"mstr_standard";
"B \NAC \NWC"2;
"S \NAC"
BN"11"157;
%"TAP"
"6","(900,4400)","2","mstr_standard","I20";
;
HDL_TAP"TRUE"
BODY_TYPE"PLUMBING"
CDS_LIB"mstr_standard";
"B \NAC \NWC"2;
"S \NAC"
BN"10"155;
%"TAP"
"6","(900,4300)","2","mstr_standard","I21";
;
HDL_TAP"TRUE"
BODY_TYPE"PLUMBING"
CDS_LIB"mstr_standard";
"B \NAC \NWC"2;
"S \NAC"
BN"9"174;
%"TAP"
"6","(900,4200)","2","mstr_standard","I22";
;
HDL_TAP"TRUE"
BODY_TYPE"PLUMBING"
CDS_LIB"mstr_standard";
"B \NAC \NWC"2;
"S \NAC"
BN"8"172;
%"TAP"
"6","(900,4100)","2","mstr_standard","I23";
;
HDL_TAP"TRUE"
BODY_TYPE"PLUMBING"
CDS_LIB"mstr_standard";
"B \NAC \NWC"2;
"S \NAC"
BN"7"170;
%"TAP"
"6","(700,4450)","2","mstr_standard","I24";
;
HDL_TAP"TRUE"
BODY_TYPE"PLUMBING"
CDS_LIB"mstr_standard";
"B \NAC \NWC"1;
"S \NAC"
BN"10"156;
%"TAP"
"6","(700,4350)","2","mstr_standard","I25";
;
HDL_TAP"TRUE"
BODY_TYPE"PLUMBING"
CDS_LIB"mstr_standard";
"B \NAC \NWC"1;
"S \NAC"
BN"9"175;
%"TAP"
"6","(700,4050)","2","mstr_standard","I26";
;
HDL_TAP"TRUE"
BODY_TYPE"PLUMBING"
CDS_LIB"mstr_standard";
"B \NAC \NWC"1;
"S \NAC"
BN"6"154;
%"TAP"
"6","(700,4150)","2","mstr_standard","I27";
;
HDL_TAP"TRUE"
BODY_TYPE"PLUMBING"
CDS_LIB"mstr_standard";
"B \NAC \NWC"1;
"S \NAC"
BN"7"171;
%"TAP"
"6","(700,4250)","2","mstr_standard","I28";
;
HDL_TAP"TRUE"
BODY_TYPE"PLUMBING"
CDS_LIB"mstr_standard";
"B \NAC \NWC"1;
"S \NAC"
BN"8"173;
%"TAP"
"6","(900,4000)","2","mstr_standard","I29";
;
HDL_TAP"TRUE"
BODY_TYPE"PLUMBING"
CDS_LIB"mstr_standard";
"B \NAC \NWC"2;
"S \NAC"
BN"6"153;
%"TAP"
"6","(900,5100)","2","mstr_standard","I3";
;
HDL_TAP"TRUE"
BODY_TYPE"PLUMBING"
CDS_LIB"mstr_standard";
"B \NAC \NWC"2;
"S \NAC"
BN"17"169;
%"TAP"
"6","(900,3900)","2","mstr_standard","I30";
;
HDL_TAP"TRUE"
BODY_TYPE"PLUMBING"
CDS_LIB"mstr_standard";
"B \NAC \NWC"2;
"S \NAC"
BN"5"151;
%"TAP"
"6","(900,3800)","2","mstr_standard","I31";
;
HDL_TAP"TRUE"
BODY_TYPE"PLUMBING"
CDS_LIB"mstr_standard";
"B \NAC \NWC"2;
"S \NAC"
BN"4"149;
%"TAP"
"6","(900,3700)","2","mstr_standard","I32";
;
HDL_TAP"TRUE"
BODY_TYPE"PLUMBING"
CDS_LIB"mstr_standard";
"B \NAC \NWC"2;
"S \NAC"
BN"3"147;
%"TAP"
"6","(900,3600)","2","mstr_standard","I33";
;
HDL_TAP"TRUE"
BODY_TYPE"PLUMBING"
CDS_LIB"mstr_standard";
"B \NAC \NWC"2;
"S \NAC"
BN"2"145;
%"TAP"
"6","(700,3950)","2","mstr_standard","I34";
;
HDL_TAP"TRUE"
BODY_TYPE"PLUMBING"
CDS_LIB"mstr_standard";
"B \NAC \NWC"1;
"S \NAC"
BN"5"152;
%"TAP"
"6","(700,3850)","2","mstr_standard","I35";
;
HDL_TAP"TRUE"
BODY_TYPE"PLUMBING"
CDS_LIB"mstr_standard";
"B \NAC \NWC"1;
"S \NAC"
BN"4"150;
%"TAP"
"6","(700,3650)","2","mstr_standard","I36";
;
HDL_TAP"TRUE"
BODY_TYPE"PLUMBING"
CDS_LIB"mstr_standard";
"B \NAC \NWC"1;
"S \NAC"
BN"2"146;
%"TAP"
"6","(700,3550)","2","mstr_standard","I37";
;
HDL_TAP"TRUE"
BODY_TYPE"PLUMBING"
CDS_LIB"mstr_standard";
"B \NAC \NWC"1;
"S \NAC"
BN"1"144;
%"TAP"
"6","(700,3750)","2","mstr_standard","I38";
;
HDL_TAP"TRUE"
BODY_TYPE"PLUMBING"
CDS_LIB"mstr_standard";
"B \NAC \NWC"1;
"S \NAC"
BN"3"148;
%"TAP"
"6","(900,3400)","2","mstr_standard","I39";
;
HDL_TAP"TRUE"
BODY_TYPE"PLUMBING"
CDS_LIB"mstr_standard";
"B \NAC \NWC"2;
"S \NAC"
BN"0"141;
%"TAP"
"6","(700,5150)","2","mstr_standard","I4";
;
HDL_TAP"TRUE"
BODY_TYPE"PLUMBING"
CDS_LIB"mstr_standard";
"B \NAC \NWC"1;
"S \NAC"
BN"17"176;
%"TAP"
"6","(900,3500)","2","mstr_standard","I40";
;
HDL_TAP"TRUE"
BODY_TYPE"PLUMBING"
CDS_LIB"mstr_standard";
"B \NAC \NWC"2;
"S \NAC"
BN"1"143;
%"TAP"
"6","(700,3450)","2","mstr_standard","I41";
;
HDL_TAP"TRUE"
BODY_TYPE"PLUMBING"
CDS_LIB"mstr_standard";
"B \NAC \NWC"1;
"S \NAC"
BN"0"142;
%"SCONN288_H44441004"
"3","(1800,2400)","0","mstr_sconn","I43";
;
CDS_SEC"3"
ROOM"DDR4_CH_L"
CDS_LOCATION"J1A2"
SEC"3"
SEC_TYPE"PIP"
CDS_LIB"mstr_sconn"
BOM_COST"MEM"
PACK_TYPE"PIP"
MATERIAL"SCONN"
PART_NUMBER"H44441-004"
LOCATION"J1A2";
"VSS<93>"
$PN"2"21;
"VSS<92>"
$PN"4"21;
"VSS<91>"
$PN"6"21;
"VSS<90>"
$PN"9"21;
"VSS<89>"
$PN"11"21;
"VSS<88>"
$PN"13"21;
"VSS<0>"
$PN"283"15;
"VSS<1>"
$PN"281"15;
"VSS<2>"
$PN"279"15;
"VSS<3>"
$PN"276"15;
"VSS<4>"
$PN"274"15;
"VSS<5>"
$PN"272"15;
"VSS<6>"
$PN"270"15;
"VSS<7>"
$PN"268"15;
"VSS<8>"
$PN"265"15;
"VSS<9>"
$PN"263"15;
"VSS<10>"
$PN"261"15;
"VSS<11>"
$PN"259"15;
"VSS<12>"
$PN"257"15;
"VSS<13>"
$PN"254"15;
"VSS<14>"
$PN"252"15;
"VSS<15>"
$PN"250"15;
"VSS<16>"
$PN"248"15;
"VSS<17>"
$PN"246"15;
"VSS<18>"
$PN"243"15;
"VSS<19>"
$PN"241"15;
"VSS<20>"
$PN"239"15;
"VSS<21>"
$PN"202"15;
"VSS<22>"
$PN"200"15;
"VSS<23>"
$PN"198"15;
"VSS<24>"
$PN"195"15;
"VSS<25>"
$PN"193"15;
"VSS<26>"
$PN"191"15;
"VSS<27>"
$PN"189"15;
"VSS<28>"
$PN"187"15;
"VSS<29>"
$PN"184"15;
"VSS<30>"
$PN"182"15;
"VSS<31>"
$PN"180"15;
"VSS<32>"
$PN"178"15;
"VSS<33>"
$PN"176"15;
"VSS<34>"
$PN"173"15;
"VSS<35>"
$PN"171"15;
"VSS<36>"
$PN"169"15;
"VSS<37>"
$PN"167"15;
"VSS<38>"
$PN"165"15;
"VSS<39>"
$PN"162"15;
"VSS<40>"
$PN"160"15;
"VSS<41>"
$PN"158"15;
"VSS<42>"
$PN"156"15;
"VSS<43>"
$PN"154"15;
"VSS<44>"
$PN"151"15;
"VSS<47>"
$PN"138"21;
"VSS<48>"
$PN"136"21;
"VSS<49>"
$PN"134"21;
"VSS<50>"
$PN"131"21;
"VSS<51>"
$PN"129"21;
"VSS<52>"
$PN"127"21;
"VSS<53>"
$PN"125"21;
"VSS<54>"
$PN"123"21;
"VSS<55>"
$PN"120"21;
"VSS<56>"
$PN"118"21;
"VSS<57>"
$PN"116"21;
"VSS<58>"
$PN"114"21;
"VSS<59>"
$PN"112"21;
"VSS<60>"
$PN"109"21;
"VSS<61>"
$PN"107"21;
"VSS<62>"
$PN"105"21;
"VSS<63>"
$PN"103"21;
"VSS<64>"
$PN"101"21;
"VSS<65>"
$PN"98"21;
"VSS<66>"
$PN"96"21;
"VSS<67>"
$PN"94"21;
"VSS<68>"
$PN"57"21;
"VSS<69>"
$PN"55"21;
"VSS<70>"
$PN"53"21;
"VSS<71>"
$PN"50"21;
"VSS<72>"
$PN"48"21;
"VSS<73>"
$PN"46"21;
"VSS<74>"
$PN"44"21;
"VSS<75>"
$PN"42"21;
"VSS<76>"
$PN"39"21;
"VSS<77>"
$PN"37"21;
"VSS<78>"
$PN"35"21;
"VSS<79>"
$PN"33"21;
"VSS<80>"
$PN"31"21;
"VSS<81>"
$PN"28"21;
"VSS<82>"
$PN"26"21;
"VSS<83>"
$PN"24"21;
"VSS<84>"
$PN"22"21;
"VSS<85>"
$PN"20"21;
"VSS<86>"
$PN"17"21;
"VSS<87>"
$PN"15"21;
"VSS<45>"
$PN"149"15;
"VSS<46>"
$PN"147"15;
%"GND"
"1","(1100,1100)","2","mstr_symbols","I44";
;
HDL_POWER"GND"
ROOM"DDR4_CH_D"
BODY_TYPE"PLUMBING"
SIZE"1B"
CDS_LIB"mstr_symbols"
BOM_COST"MEM"
VOLTAGE"0";
"A\NAC"21;
%"TAP"
"6","(-1750,4800)","2","mstr_standard","I46";
;
HDL_TAP"TRUE"
BODY_TYPE"PLUMBING"
CDS_LIB"mstr_standard";
"B \NAC \NWC"4;
"S \NAC"
BN"60"135;
%"TAP"
"6","(-1750,4750)","2","mstr_standard","I47";
;
HDL_TAP"TRUE"
BODY_TYPE"PLUMBING"
CDS_LIB"mstr_standard";
"B \NAC \NWC"4;
"S \NAC"
BN"61"137;
%"TAP"
"6","(-1750,4850)","2","mstr_standard","I48";
;
HDL_TAP"TRUE"
BODY_TYPE"PLUMBING"
CDS_LIB"mstr_standard";
"B \NAC \NWC"4;
"S \NAC"
BN"63"139;
%"TAP"
"6","(-1750,4900)","2","mstr_standard","I49";
;
HDL_TAP"TRUE"
BODY_TYPE"PLUMBING"
CDS_LIB"mstr_standard";
"B \NAC \NWC"4;
"S \NAC"
BN"62"140;
%"TAP"
"6","(900,5000)","2","mstr_standard","I5";
;
HDL_TAP"TRUE"
BODY_TYPE"PLUMBING"
CDS_LIB"mstr_standard";
"B \NAC \NWC"2;
"S \NAC"
BN"16"167;
%"TAP"
"6","(-1750,4500)","2","mstr_standard","I50";
;
HDL_TAP"TRUE"
BODY_TYPE"PLUMBING"
CDS_LIB"mstr_standard";
"B \NAC \NWC"4;
"S \NAC"
BN"54"130;
%"TAP"
"6","(-1750,4550)","2","mstr_standard","I51";
;
HDL_TAP"TRUE"
BODY_TYPE"PLUMBING"
CDS_LIB"mstr_standard";
"B \NAC \NWC"4;
"S \NAC"
BN"57"131;
%"TAP"
"6","(-1750,4650)","2","mstr_standard","I52";
;
HDL_TAP"TRUE"
BODY_TYPE"PLUMBING"
CDS_LIB"mstr_standard";
"B \NAC \NWC"4;
"S \NAC"
BN"59"136;
%"TAP"
"6","(-1750,4600)","2","mstr_standard","I53";
;
HDL_TAP"TRUE"
BODY_TYPE"PLUMBING"
CDS_LIB"mstr_standard";
"B \NAC \NWC"4;
"S \NAC"
BN"56"132;
%"TAP"
"6","(-1750,4700)","2","mstr_standard","I54";
;
HDL_TAP"TRUE"
BODY_TYPE"PLUMBING"
CDS_LIB"mstr_standard";
"B \NAC \NWC"4;
"S \NAC"
BN"58"138;
%"TAP"
"6","(-1750,4250)","2","mstr_standard","I55";
;
HDL_TAP"TRUE"
BODY_TYPE"PLUMBING"
CDS_LIB"mstr_standard";
"B \NAC \NWC"4;
"S \NAC"
BN"51"127;
%"TAP"
"6","(-1750,4300)","2","mstr_standard","I56";
;
HDL_TAP"TRUE"
BODY_TYPE"PLUMBING"
CDS_LIB"mstr_standard";
"B \NAC \NWC"4;
"S \NAC"
BN"50"128;
%"TAP"
"6","(-1750,4350)","2","mstr_standard","I57";
;
HDL_TAP"TRUE"
BODY_TYPE"PLUMBING"
CDS_LIB"mstr_standard";
"B \NAC \NWC"4;
"S \NAC"
BN"53"129;
%"TAP"
"6","(-1750,4450)","2","mstr_standard","I58";
;
HDL_TAP"TRUE"
BODY_TYPE"PLUMBING"
CDS_LIB"mstr_standard";
"B \NAC \NWC"4;
"S \NAC"
BN"55"133;
%"TAP"
"6","(-1750,4400)","2","mstr_standard","I59";
;
HDL_TAP"TRUE"
BODY_TYPE"PLUMBING"
CDS_LIB"mstr_standard";
"B \NAC \NWC"4;
"S \NAC"
BN"52"134;
%"TAP"
"6","(900,4900)","2","mstr_standard","I6";
;
HDL_TAP"TRUE"
BODY_TYPE"PLUMBING"
CDS_LIB"mstr_standard";
"B \NAC \NWC"2;
"S \NAC"
BN"15"165;
%"TAP"
"6","(-1750,3950)","2","mstr_standard","I60";
;
HDL_TAP"TRUE"
BODY_TYPE"PLUMBING"
CDS_LIB"mstr_standard";
"B \NAC \NWC"4;
"S \NAC"
BN"45"103;
%"TAP"
"6","(-1750,4000)","2","mstr_standard","I61";
;
HDL_TAP"TRUE"
BODY_TYPE"PLUMBING"
CDS_LIB"mstr_standard";
"B \NAC \NWC"4;
"S \NAC"
BN"44"104;
%"TAP"
"6","(-1750,4050)","2","mstr_standard","I62";
;
HDL_TAP"TRUE"
BODY_TYPE"PLUMBING"
CDS_LIB"mstr_standard";
"B \NAC \NWC"4;
"S \NAC"
BN"47"105;
%"TAP"
"6","(-1750,4150)","2","mstr_standard","I63";
;
HDL_TAP"TRUE"
BODY_TYPE"PLUMBING"
CDS_LIB"mstr_standard";
"B \NAC \NWC"4;
"S \NAC"
BN"49"125;
%"TAP"
"6","(-1750,4100)","2","mstr_standard","I64";
;
HDL_TAP"TRUE"
BODY_TYPE"PLUMBING"
CDS_LIB"mstr_standard";
"B \NAC \NWC"4;
"S \NAC"
BN"46"124;
%"TAP"
"6","(-1750,4200)","2","mstr_standard","I65";
;
HDL_TAP"TRUE"
BODY_TYPE"PLUMBING"
CDS_LIB"mstr_standard";
"B \NAC \NWC"4;
"S \NAC"
BN"48"126;
%"SCONN288_H44441004"
"2","(0,4300)","0","mstr_sconn","I66";
;
CDS_SEC"2"
ROOM"DDR4_CH_L"
CDS_LOCATION"J1A2"
SEC"2"
SEC_TYPE"PIP"
CDS_LIB"mstr_sconn"
BOM_COST"MEM"
PACK_TYPE"PIP"
MATERIAL"SCONN"
PART_NUMBER"H44441-004"
LOCATION"J1A2";
"DQS17P"
$PN"51"176;
"DQS9P"
$PN"7"175;
"DQS9N"
$PN"8"174;
"DQS8P"
$PN"197"173;
"DQS8N"
$PN"196"172;
"DQS7P"
$PN"278"171;
"DQS7N"
$PN"277"170;
"DQS6P"
$PN"267"154;
"DQS6N"
$PN"266"153;
"DQS5P"
$PN"256"152;
"DQS5N"
$PN"255"151;
"DQS4P"
$PN"245"150;
"DQS4N"
$PN"244"149;
"DQS3P"
$PN"186"148;
"DQS3N"
$PN"185"147;
"DQS2P"
$PN"175"146;
"DQS2N"
$PN"174"145;
"DQS1P"
$PN"164"144;
"DQS1N"
$PN"163"143;
"DQS17N"
$PN"52"169;
"DQS16P"
$PN"132"168;
"DQS16N"
$PN"133"167;
"DQS15P"
$PN"121"166;
"DQS15N"
$PN"122"165;
"DQS14P"
$PN"110"164;
"DQS14N"
$PN"111"163;
"DQS13P"
$PN"99"162;
"DQS13N"
$PN"100"161;
"DQS12P"
$PN"40"160;
"DQS12N"
$PN"41"159;
"DQS11P"
$PN"29"158;
"DQS11N"
$PN"30"157;
"DQS10P"
$PN"18"156;
"DQS10N"
$PN"19"155;
"DQS0P"
$PN"153"142;
"DQS0N"
$PN"152"141;
%"TAP"
"6","(-1750,3800)","2","mstr_standard","I67";
;
HDL_TAP"TRUE"
BODY_TYPE"PLUMBING"
CDS_LIB"mstr_standard";
"B \NAC \NWC"4;
"S \NAC"
BN"40"99;
%"TAP"
"6","(-1750,3700)","2","mstr_standard","I68";
;
HDL_TAP"TRUE"
BODY_TYPE"PLUMBING"
CDS_LIB"mstr_standard";
"B \NAC \NWC"4;
"S \NAC"
BN"38"98;
%"TAP"
"6","(-1750,3750)","2","mstr_standard","I69";
;
HDL_TAP"TRUE"
BODY_TYPE"PLUMBING"
CDS_LIB"mstr_standard";
"B \NAC \NWC"4;
"S \NAC"
BN"41"100;
%"TAP"
"6","(900,4800)","2","mstr_standard","I7";
;
HDL_TAP"TRUE"
BODY_TYPE"PLUMBING"
CDS_LIB"mstr_standard";
"B \NAC \NWC"2;
"S \NAC"
BN"14"163;
%"TAP"
"6","(-1750,3850)","2","mstr_standard","I70";
;
HDL_TAP"TRUE"
BODY_TYPE"PLUMBING"
CDS_LIB"mstr_standard";
"B \NAC \NWC"4;
"S \NAC"
BN"43"106;
%"TAP"
"6","(-1750,3900)","2","mstr_standard","I71";
;
HDL_TAP"TRUE"
BODY_TYPE"PLUMBING"
CDS_LIB"mstr_standard";
"B \NAC \NWC"4;
"S \NAC"
BN"42"102;
%"TAP"
"6","(-1750,3500)","2","mstr_standard","I72";
;
HDL_TAP"TRUE"
BODY_TYPE"PLUMBING"
CDS_LIB"mstr_standard";
"B \NAC \NWC"4;
"S \NAC"
BN"34"95;
%"TAP"
"6","(-1750,3450)","2","mstr_standard","I73";
;
HDL_TAP"TRUE"
BODY_TYPE"PLUMBING"
CDS_LIB"mstr_standard";
"B \NAC \NWC"4;
"S \NAC"
BN"35"93;
%"TAP"
"6","(-1750,3550)","2","mstr_standard","I74";
;
HDL_TAP"TRUE"
BODY_TYPE"PLUMBING"
CDS_LIB"mstr_standard";
"B \NAC \NWC"4;
"S \NAC"
BN"37"96;
%"TAP"
"6","(-1750,3600)","2","mstr_standard","I75";
;
HDL_TAP"TRUE"
BODY_TYPE"PLUMBING"
CDS_LIB"mstr_standard";
"B \NAC \NWC"4;
"S \NAC"
BN"36"97;
%"TAP"
"6","(-1750,3650)","2","mstr_standard","I76";
;
HDL_TAP"TRUE"
BODY_TYPE"PLUMBING"
CDS_LIB"mstr_standard";
"B \NAC \NWC"4;
"S \NAC"
BN"39"101;
%"TAP"
"6","(-1750,3250)","2","mstr_standard","I77";
;
HDL_TAP"TRUE"
BODY_TYPE"PLUMBING"
CDS_LIB"mstr_standard";
"B \NAC \NWC"4;
"S \NAC"
BN"31"90;
%"TAP"
"6","(-1750,3300)","2","mstr_standard","I78";
;
HDL_TAP"TRUE"
BODY_TYPE"PLUMBING"
CDS_LIB"mstr_standard";
"B \NAC \NWC"4;
"S \NAC"
BN"30"89;
%"TAP"
"6","(-1750,3200)","2","mstr_standard","I79";
;
HDL_TAP"TRUE"
BODY_TYPE"PLUMBING"
CDS_LIB"mstr_standard";
"B \NAC \NWC"4;
"S \NAC"
BN"28"87;
%"TAP"
"6","(900,4700)","2","mstr_standard","I8";
;
HDL_TAP"TRUE"
BODY_TYPE"PLUMBING"
CDS_LIB"mstr_standard";
"B \NAC \NWC"2;
"S \NAC"
BN"13"161;
%"TAP"
"6","(-1750,3350)","2","mstr_standard","I80";
;
HDL_TAP"TRUE"
BODY_TYPE"PLUMBING"
CDS_LIB"mstr_standard";
"B \NAC \NWC"4;
"S \NAC"
BN"33"94;
%"TAP"
"6","(-1750,3400)","2","mstr_standard","I81";
;
HDL_TAP"TRUE"
BODY_TYPE"PLUMBING"
CDS_LIB"mstr_standard";
"B \NAC \NWC"4;
"S \NAC"
BN"32"92;
%"TAP"
"6","(-1750,3000)","2","mstr_standard","I82";
;
HDL_TAP"TRUE"
BODY_TYPE"PLUMBING"
CDS_LIB"mstr_standard";
"B \NAC \NWC"4;
"S \NAC"
BN"24"85;
%"TAP"
"6","(-1750,2950)","2","mstr_standard","I83";
;
HDL_TAP"TRUE"
BODY_TYPE"PLUMBING"
CDS_LIB"mstr_standard";
"B \NAC \NWC"4;
"S \NAC"
BN"25"84;
%"TAP"
"6","(-1750,3050)","2","mstr_standard","I84";
;
HDL_TAP"TRUE"
BODY_TYPE"PLUMBING"
CDS_LIB"mstr_standard";
"B \NAC \NWC"4;
"S \NAC"
BN"27"86;
%"TAP"
"6","(-1750,3150)","2","mstr_standard","I85";
;
HDL_TAP"TRUE"
BODY_TYPE"PLUMBING"
CDS_LIB"mstr_standard";
"B \NAC \NWC"4;
"S \NAC"
BN"29"88;
%"TAP"
"6","(-1750,3100)","2","mstr_standard","I86";
;
HDL_TAP"TRUE"
BODY_TYPE"PLUMBING"
CDS_LIB"mstr_standard";
"B \NAC \NWC"4;
"S \NAC"
BN"26"91;
%"TAP"
"6","(-1750,2700)","2","mstr_standard","I87";
;
HDL_TAP"TRUE"
BODY_TYPE"PLUMBING"
CDS_LIB"mstr_standard";
"B \NAC \NWC"4;
"S \NAC"
BN"18"77;
%"TAP"
"6","(-1750,2750)","2","mstr_standard","I88";
;
HDL_TAP"TRUE"
BODY_TYPE"PLUMBING"
CDS_LIB"mstr_standard";
"B \NAC \NWC"4;
"S \NAC"
BN"21"79;
%"TAP"
"6","(-1750,2800)","2","mstr_standard","I89";
;
HDL_TAP"TRUE"
BODY_TYPE"PLUMBING"
CDS_LIB"mstr_standard";
"B \NAC \NWC"4;
"S \NAC"
BN"20"78;
%"TAP"
"6","(900,4600)","2","mstr_standard","I9";
;
HDL_TAP"TRUE"
BODY_TYPE"PLUMBING"
CDS_LIB"mstr_standard";
"B \NAC \NWC"2;
"S \NAC"
BN"12"159;
%"TAP"
"6","(-1750,2900)","2","mstr_standard","I90";
;
HDL_TAP"TRUE"
BODY_TYPE"PLUMBING"
CDS_LIB"mstr_standard";
"B \NAC \NWC"4;
"S \NAC"
BN"22"83;
%"TAP"
"6","(-1750,2850)","2","mstr_standard","I91";
;
HDL_TAP"TRUE"
BODY_TYPE"PLUMBING"
CDS_LIB"mstr_standard";
"B \NAC \NWC"4;
"S \NAC"
BN"23"82;
%"TAP"
"6","(-1750,2450)","2","mstr_standard","I92";
;
HDL_TAP"TRUE"
BODY_TYPE"PLUMBING"
CDS_LIB"mstr_standard";
"B \NAC \NWC"4;
"S \NAC"
BN"15"73;
%"TAP"
"6","(-1750,2500)","2","mstr_standard","I93";
;
HDL_TAP"TRUE"
BODY_TYPE"PLUMBING"
CDS_LIB"mstr_standard";
"B \NAC \NWC"4;
"S \NAC"
BN"14"76;
%"TAP"
"6","(-1750,2600)","2","mstr_standard","I94";
;
HDL_TAP"TRUE"
BODY_TYPE"PLUMBING"
CDS_LIB"mstr_standard";
"B \NAC \NWC"4;
"S \NAC"
BN"16"81;
%"TAP"
"6","(-1750,2550)","2","mstr_standard","I95";
;
HDL_TAP"TRUE"
BODY_TYPE"PLUMBING"
CDS_LIB"mstr_standard";
"B \NAC \NWC"4;
"S \NAC"
BN"17"72;
%"TAP"
"6","(-1750,2650)","2","mstr_standard","I96";
;
HDL_TAP"TRUE"
BODY_TYPE"PLUMBING"
CDS_LIB"mstr_standard";
"B \NAC \NWC"4;
"S \NAC"
BN"19"80;
%"TAP"
"6","(-1750,2400)","2","mstr_standard","I97";
;
HDL_TAP"TRUE"
BODY_TYPE"PLUMBING"
CDS_LIB"mstr_standard";
"B \NAC \NWC"4;
"S \NAC"
BN"12"74;
%"TAP"
"6","(-1750,2300)","2","mstr_standard","I98";
;
HDL_TAP"TRUE"
BODY_TYPE"PLUMBING"
CDS_LIB"mstr_standard";
"B \NAC \NWC"4;
"S \NAC"
BN"10"66;
%"TAP"
"6","(-1750,2350)","2","mstr_standard","I99";
;
HDL_TAP"TRUE"
BODY_TYPE"PLUMBING"
CDS_LIB"mstr_standard";
"B \NAC \NWC"4;
"S \NAC"
BN"13"75;
END.
